# T6G (Grand Teton) — schematic netlist excerpt (pin names and nets, part order shuffled) for the footprints in the layout excerpt that follows; sources: Cadence DE-HDL packaged netlist, KiCad conversion of 04192023_DAF0TMB3IC0_F0TG_MB_C_brd_V02_OCP.brd

C6680  Q_CAP_DIFFBUS  DIFF BUS_0.22UF 6.3V 20% X6S  pkg C0201  page 330 : \1\ = P5E_CPU1_P1_TX_BUF_C_DN<9> ; \2\ = P5E_CPU1_P1_TX_BUF_DN<9>
C312  Q_CAP  0.1UF 10V 10% X7S  pkg C0201  page 334 : A = P0V9_CPU1_RT1_2A ; B = GND
C6060  Q_CAP  0.001UF 50V 10% X7R  pkg C0402  page 177 : A = P1V2_AUX ; B = GND

(kicad_pcb
	(version 20260206)
	(generator "pcbnew")
	(generator_version "10.0")
	(general
		(thickness 1.6)
		(legacy_teardrops no)
	)
	(paper "A4")
	(title_block
		(title "04192023_DAF0TMB3IC0_F0TG_MB_C_brd_V02_OCP.brd")
		(comment 1 "Grand Teton / footprints 5156-5158 of 8354")
	)
	(layers
		(0 "F.Cu" signal "TOP")
		(4 "In1.Cu" signal "GND")
		(6 "In2.Cu" signal "IN1")
		(8 "In3.Cu" signal "GND1")
		(10 "In4.Cu" signal "IN2")
		(12 "In5.Cu" signal "GND2")
		(14 "In6.Cu" signal "IN3")
		(16 "In7.Cu" signal "GND3")
		(18 "In8.Cu" signal "VCC")
		(20 "In9.Cu" signal "VCC1")
		(22 "In10.Cu" signal "GND4")
		(24 "In11.Cu" signal "IN4")
		(26 "In12.Cu" signal "GND5")
		(28 "In13.Cu" signal "IN5")
		(30 "In14.Cu" signal "GND6")
		(32 "In15.Cu" signal "IN6")
		(34 "In16.Cu" signal "GND7")
		(2 "B.Cu" signal "BOTTOM")
		(9 "F.Adhes" user "F.Adhesive")
		(11 "B.Adhes" user "B.Adhesive")
		(13 "F.Paste" user "Package Geometry/Pastemask Top")
		(15 "B.Paste" user "Package Geometry/Pastemask Bottom")
		(5 "F.SilkS" user "Ref Des/Silkscreen Top")
		(7 "B.SilkS" user "Ref Des/Silkscreen Bottom")
		(1 "F.Mask" user "Board Geometry/Soldermask Top")
		(3 "B.Mask" user "Board Geometry/Soldermask Bottom")
		(17 "Dwgs.User" user "User.Drawings")
		(19 "Cmts.User" user "User.Comments")
		(21 "Eco1.User" user "User.Eco1")
		(23 "Eco2.User" user "User.Eco2")
		(25 "Edge.Cuts" user "Board Geometry/Outline")
		(27 "Margin" user)
		(31 "F.CrtYd" user "Package Geometry/Place Bound Top")
		(29 "B.CrtYd" user "Package Geometry/Place Bound Bottom")
		(35 "F.Fab" user "Ref Des/Assembly Top")
		(33 "B.Fab" user "Ref Des/Assembly Bottom")
	)
	(footprint ""
		(layer "B.Cu")
		(at 77.627734 -388.609078 90)
		(property "Reference" "C312"
			(at 0 0 90)
			(layer "B.SilkS")
			(hide yes)
			(effects
				(font
					(size 1.27 1.27)
				)
				(justify mirror)
			)
		)
		(property "Value" ""
			(at 0 0 90)
			(layer "B.Fab")
			(effects
				(font
					(size 1.27 1.27)
				)
				(justify mirror)
			)
		)
		(duplicate_pad_numbers_are_jumpers no)
		(fp_line
			(start 0.299974 -0.150114)
			(end -0.299974 -0.150114)
			(stroke
				(width 0.1)
				(type default)
			)
			(layer "B.Fab")
		)
		(fp_line
			(start -0.299974 -0.150114)
			(end -0.299974 0.150114)
			(stroke
				(width 0.1)
				(type default)
			)
			(layer "B.Fab")
		)
		(fp_line
			(start 0.299974 0.150114)
			(end 0.299974 -0.150114)
			(stroke
				(width 0.1)
				(type default)
			)
			(layer "B.Fab")
		)
		(fp_line
			(start -0.299974 0.150114)
			(end 0.299974 0.150114)
			(stroke
				(width 0.1)
				(type default)
			)
			(layer "B.Fab")
		)
		(pad "1" smd rect
			(at 0.2667 0 270)
			(size 0.3048 0.381)
			(layers "B.Cu" "B.Mask" "B.Paste")
			(net "P0V9_CPU1_RT1_2A")
		)
		(pad "2" smd rect
			(at -0.2667 0 270)
			(size 0.3048 0.381)
			(layers "B.Cu" "B.Mask" "B.Paste")
			(net "GND")
		)
	)
	(footprint ""
		(layer "B.Cu")
		(at 126.911608 -38.87343 90)
		(property "Reference" "C6060"
			(at 0 0 90)
			(layer "B.SilkS")
			(hide yes)
			(effects
				(font
					(size 1.27 1.27)
				)
				(justify mirror)
			)
		)
		(property "Value" ""
			(at 0 0 90)
			(layer "B.Fab")
			(effects
				(font
					(size 1.27 1.27)
				)
				(justify mirror)
			)
		)
		(duplicate_pad_numbers_are_jumpers no)
		(fp_line
			(start 0.7874 -0.4064)
			(end -0.7874 -0.4064)
			(stroke
				(width 0.1524)
				(type default)
			)
			(layer "B.SilkS")
		)
		(fp_line
			(start -0.7874 -0.4064)
			(end -0.7874 0.4064)
			(stroke
				(width 0.1524)
				(type default)
			)
			(layer "B.SilkS")
		)
		(fp_line
			(start 0.7874 0.4064)
			(end 0.7874 -0.4064)
			(stroke
				(width 0.1524)
				(type default)
			)
			(layer "B.SilkS")
		)
		(fp_line
			(start -0.7874 0.4064)
			(end 0.7874 0.4064)
			(stroke
				(width 0.1524)
				(type default)
			)
			(layer "B.SilkS")
		)
		(fp_line
			(start 0.67945 -0.305054)
			(end 0.12065 -0.305054)
			(stroke
				(width 0.1)
				(type default)
			)
			(layer "B.Fab")
		)
		(fp_line
			(start 0.12065 -0.305054)
			(end 0.12065 -0.2794)
			(stroke
				(width 0.1)
				(type default)
			)
			(layer "B.Fab")
		)
		(fp_line
			(start -0.12065 -0.3048)
			(end -0.67945 -0.3048)
			(stroke
				(width 0.1)
				(type default)
			)
			(layer "B.Fab")
		)
		(fp_line
			(start -0.67945 -0.3048)
			(end -0.67945 0.3048)
			(stroke
				(width 0.1)
				(type default)
			)
			(layer "B.Fab")
		)
		(fp_line
			(start 0.12065 -0.2794)
			(end -0.12065 -0.2794)
			(stroke
				(width 0.1)
				(type default)
			)
			(layer "B.Fab")
		)
		(fp_line
			(start -0.12065 -0.2794)
			(end -0.12065 -0.3048)
			(stroke
				(width 0.1)
				(type default)
			)
			(layer "B.Fab")
		)
		(fp_line
			(start 0.12065 0.2794)
			(end 0.12065 0.3048)
			(stroke
				(width 0.1)
				(type default)
			)
			(layer "B.Fab")
		)
		(fp_line
			(start -0.120396 0.2794)
			(end 0.12065 0.2794)
			(stroke
				(width 0.1)
				(type default)
			)
			(layer "B.Fab")
		)
		(fp_line
			(start 0.67945 0.3048)
			(end 0.67945 -0.305054)
			(stroke
				(width 0.1)
				(type default)
			)
			(layer "B.Fab")
		)
		(fp_line
			(start 0.12065 0.3048)
			(end 0.67945 0.3048)
			(stroke
				(width 0.1)
				(type default)
			)
			(layer "B.Fab")
		)
		(fp_line
			(start -0.120396 0.3048)
			(end -0.120396 0.2794)
			(stroke
				(width 0.1)
				(type default)
			)
			(layer "B.Fab")
		)
		(fp_line
			(start -0.67945 0.3048)
			(end -0.120396 0.3048)
			(stroke
				(width 0.1)
				(type default)
			)
			(layer "B.Fab")
		)
		(pad "1" smd circle
			(at 0.40005 0 270)
			(size 0 0)
			(layers "B.Cu" "B.Mask" "B.Paste")
			(net "P1V2_AUX")
		)
		(pad "2" smd circle
			(at -0.40005 0 270)
			(size 0 0)
			(layers "B.Cu" "B.Mask" "B.Paste")
			(net "GND")
		)
	)
	(footprint ""
		(layer "B.Cu")
		(at 76.869544 -408.517344 90)
		(property "Reference" "C6680"
			(at 0 0 90)
			(layer "B.SilkS")
			(hide yes)
			(effects
				(font
					(size 1.27 1.27)
				)
				(justify mirror)
			)
		)
		(property "Value" ""
			(at 0 0 90)
			(layer "B.Fab")
			(effects
				(font
					(size 1.27 1.27)
				)
				(justify mirror)
			)
		)
		(duplicate_pad_numbers_are_jumpers no)
		(fp_line
			(start 0.299974 -0.150114)
			(end -0.299974 -0.150114)
			(stroke
				(width 0.1)
				(type default)
			)
			(layer "B.Fab")
		)
		(fp_line
			(start -0.299974 -0.150114)
			(end -0.299974 0.150114)
			(stroke
				(width 0.1)
				(type default)
			)
			(layer "B.Fab")
		)
		(fp_line
			(start 0.299974 0.150114)
			(end 0.299974 -0.150114)
			(stroke
				(width 0.1)
				(type default)
			)
			(layer "B.Fab")
		)
		(fp_line
			(start -0.299974 0.150114)
			(end 0.299974 0.150114)
			(stroke
				(width 0.1)
				(type default)
			)
			(layer "B.Fab")
		)
		(pad "1" smd rect
			(at 0.2667 0 270)
			(size 0.3048 0.381)
			(layers "B.Cu" "B.Mask" "B.Paste")
			(net "P5E_CPU1_P1_TX_BUF_C_DN<9>")
		)
		(pad "2" smd rect
			(at -0.2667 0 270)
			(size 0.3048 0.381)
			(layers "B.Cu" "B.Mask" "B.Paste")
			(net "P5E_CPU1_P1_TX_BUF_DN<9>")
		)
	)
)
